# SCM (Grand Teton) — schematic netlist excerpt (pin names and nets, part order shuffled) for the footprints in the layout excerpt that follows; sources: Cadence DE-HDL packaged netlist, KiCad conversion of 12092022_DA0F0TMDCD0_F0T_Management_Board_D_brd_V3_OCP.brd

R862  Q_RES  22 1% CHIP  pkg 0402LF  page 44 : A = SPI_SYS_WP_R_IO2 ; B = SPI_SYS_MUX_WP_IO2
D1  Q_LED  IC  pkg SMLF  page 47 : A = LED_POSTCODE_1_R ; C = GND

(kicad_pcb
	(version 20260206)
	(generator "pcbnew")
	(generator_version "10.0")
	(general
		(thickness 1.6)
		(legacy_teardrops no)
	)
	(paper "A4")
	(title_block
		(title "12092022_DA0F0TMDCD0_F0T_Management_Board_D_brd_V3_OCP.brd")
		(comment 1 "Grand Teton / footprints 110-111 of 1440")
	)
	(layers
		(0 "F.Cu" signal "TOP")
		(4 "In1.Cu" signal "GND")
		(6 "In2.Cu" signal "IN1")
		(8 "In3.Cu" signal "GND1")
		(10 "In4.Cu" signal "IN2")
		(12 "In5.Cu" signal "VCC")
		(14 "In6.Cu" signal "VCC1")
		(16 "In7.Cu" signal "IN3")
		(18 "In8.Cu" signal "GND2")
		(20 "In9.Cu" signal "IN4")
		(22 "In10.Cu" signal "GND3")
		(2 "B.Cu" signal "BOTTOM")
		(9 "F.Adhes" user "F.Adhesive")
		(11 "B.Adhes" user "B.Adhesive")
		(13 "F.Paste" user "Package Geometry/Pastemask Top")
		(15 "B.Paste" user "Package Geometry/Pastemask Bottom")
		(5 "F.SilkS" user "Ref Des/Silkscreen Top")
		(7 "B.SilkS" user "Ref Des/Silkscreen Bottom")
		(1 "F.Mask" user "Board Geometry/Soldermask Top")
		(3 "B.Mask" user "Board Geometry/Soldermask Bottom")
		(17 "Dwgs.User" user "User.Drawings")
		(19 "Cmts.User" user "User.Comments")
		(21 "Eco1.User" user "User.Eco1")
		(23 "Eco2.User" user "User.Eco2")
		(25 "Edge.Cuts" user "Board Geometry/Outline")
		(27 "Margin" user)
		(31 "F.CrtYd" user "Package Geometry/Place Bound Top")
		(29 "B.CrtYd" user "Package Geometry/Place Bound Bottom")
		(35 "F.Fab" user "Ref Des/Assembly Top")
		(33 "B.Fab" user "Ref Des/Assembly Bottom")
	)
	(footprint ""
		(layer "F.Cu")
		(at 77.281786 -27.738832 90)
		(property "Reference" "D1"
			(at -1.780032 7.911084 90)
			(unlocked yes)
			(layer "F.SilkS")
			(effects
				(font
					(size 0.7874 0.5842)
					(thickness 0.1524)
				)
				(justify left)
			)
		)
		(property "Value" ""
			(at 0 0 90)
			(layer "F.Fab")
			(effects
				(font
					(size 1.27 1.27)
				)
			)
		)
		(duplicate_pad_numbers_are_jumpers no)
		(fp_line
			(start 1.778 -0.5588)
			(end 1.3208 -0.5588)
			(stroke
				(width 0.1524)
				(type default)
			)
			(layer "F.SilkS")
		)
		(fp_line
			(start 1.778 -0.5588)
			(end 1.778 0.5588)
			(stroke
				(width 0.1524)
				(type default)
			)
			(layer "F.SilkS")
		)
		(fp_line
			(start 1.4732 -0.5588)
			(end 1.4732 0.5588)
			(stroke
				(width 0.1524)
				(type default)
			)
			(layer "F.SilkS")
		)
		(fp_line
			(start 1.3208 -0.5588)
			(end 1.3208 0.5588)
			(stroke
				(width 0.1524)
				(type default)
			)
			(layer "F.SilkS")
		)
		(fp_line
			(start -1.3208 -0.5588)
			(end 1.3208 -0.5588)
			(stroke
				(width 0.1524)
				(type default)
			)
			(layer "F.SilkS")
		)
		(fp_line
			(start 1.778 0.5588)
			(end 1.3208 0.5588)
			(stroke
				(width 0.1524)
				(type default)
			)
			(layer "F.SilkS")
		)
		(fp_line
			(start 1.6256 0.5588)
			(end 1.6256 -0.5588)
			(stroke
				(width 0.1524)
				(type default)
			)
			(layer "F.SilkS")
		)
		(fp_line
			(start 1.3208 0.5588)
			(end -1.3208 0.5588)
			(stroke
				(width 0.1524)
				(type default)
			)
			(layer "F.SilkS")
		)
		(fp_line
			(start -1.3208 0.5588)
			(end -1.3208 -0.5588)
			(stroke
				(width 0.1524)
				(type default)
			)
			(layer "F.SilkS")
		)
		(fp_line
			(start 1.236726 -0.508)
			(end 1.1684 -0.508)
			(stroke
				(width 0.1)
				(type default)
			)
			(layer "F.Fab")
		)
		(fp_line
			(start 1.1684 -0.508)
			(end -1.1684 -0.508)
			(stroke
				(width 0.1)
				(type default)
			)
			(layer "F.Fab")
		)
		(fp_line
			(start -1.1684 -0.508)
			(end -1.235964 -0.508)
			(stroke
				(width 0.1)
				(type default)
			)
			(layer "F.Fab")
		)
		(fp_line
			(start -1.235964 -0.508)
			(end -1.235964 0.508)
			(stroke
				(width 0.1)
				(type default)
			)
			(layer "F.Fab")
		)
		(fp_line
			(start 1.236726 0.508)
			(end 1.236726 -0.508)
			(stroke
				(width 0.1)
				(type default)
			)
			(layer "F.Fab")
		)
		(fp_line
			(start 1.1684 0.508)
			(end 1.236726 0.508)
			(stroke
				(width 0.1)
				(type default)
			)
			(layer "F.Fab")
		)
		(fp_line
			(start -1.1684 0.508)
			(end 1.1684 0.508)
			(stroke
				(width 0.1)
				(type default)
			)
			(layer "F.Fab")
		)
		(fp_line
			(start -1.235964 0.508)
			(end -1.1684 0.508)
			(stroke
				(width 0.1)
				(type default)
			)
			(layer "F.Fab")
		)
		(fp_text user "+"
			(at -2.669032 -0.186436 90)
			(unlocked yes)
			(layer "F.SilkS")
			(effects
				(font
					(size 1.905 1.4224)
					(thickness 0.1524)
				)
				(justify left)
			)
		)
		(fp_text user "-"
			(at 0.675386 0.592582 90)
			(unlocked yes)
			(layer "F.SilkS")
			(effects
				(font
					(size 1.905 1.4224)
					(thickness 0.1524)
				)
				(justify left)
			)
		)
		(fp_text user "-"
			(at 1.524 -0.24765 90)
			(unlocked yes)
			(layer "F.Fab")
			(effects
				(font
					(size 1.905 1.4224)
					(thickness 0.1524)
				)
				(justify left)
			)
		)
		(fp_text user "+"
			(at -2.5654 -0.24765 90)
			(unlocked yes)
			(layer "F.Fab")
			(effects
				(font
					(size 1.905 1.4224)
					(thickness 0.1524)
				)
				(justify left)
			)
		)
		(pad "A" smd rect
			(at -0.750062 0 90)
			(size 0.8128 0.8128)
			(layers "F.Cu" "F.Mask" "F.Paste")
			(net "LED_POSTCODE_1_R")
		)
		(pad "C" smd rect
			(at 0.750062 0 90)
			(size 0.8128 0.8128)
			(layers "F.Cu" "F.Mask" "F.Paste")
			(net "GND")
		)
	)
	(footprint ""
		(layer "F.Cu")
		(at 52.9082 -106.5784 180)
		(property "Reference" "R862"
			(at 0 0 180)
			(layer "F.SilkS")
			(hide yes)
			(effects
				(font
					(size 1.27 1.27)
				)
			)
		)
		(property "Value" ""
			(at 0 0 180)
			(layer "F.Fab")
			(effects
				(font
					(size 1.27 1.27)
				)
			)
		)
		(duplicate_pad_numbers_are_jumpers no)
		(fp_line
			(start 0.7874 0.4064)
			(end -0.7874 0.4064)
			(stroke
				(width 0.1524)
				(type default)
			)
			(layer "F.SilkS")
		)
		(fp_line
			(start 0.7874 -0.4064)
			(end 0.7874 0.4064)
			(stroke
				(width 0.1524)
				(type default)
			)
			(layer "F.SilkS")
		)
		(fp_line
			(start -0.7874 0.4064)
			(end -0.7874 -0.4064)
			(stroke
				(width 0.1524)
				(type default)
			)
			(layer "F.SilkS")
		)
		(fp_line
			(start -0.7874 -0.4064)
			(end 0.7874 -0.4064)
			(stroke
				(width 0.1524)
				(type default)
			)
			(layer "F.SilkS")
		)
		(fp_line
			(start 0.67945 0.3048)
			(end 0.120396 0.3048)
			(stroke
				(width 0.1)
				(type default)
			)
			(layer "F.Fab")
		)
		(fp_line
			(start 0.67945 -0.3048)
			(end 0.67945 0.3048)
			(stroke
				(width 0.1)
				(type default)
			)
			(layer "F.Fab")
		)
		(fp_line
			(start 0.12065 -0.2794)
			(end 0.12065 -0.3048)
			(stroke
				(width 0.1)
				(type default)
			)
			(layer "F.Fab")
		)
		(fp_line
			(start 0.12065 -0.3048)
			(end 0.67945 -0.3048)
			(stroke
				(width 0.1)
				(type default)
			)
			(layer "F.Fab")
		)
		(fp_line
			(start 0.120396 0.3048)
			(end 0.120396 0.2794)
			(stroke
				(width 0.1)
				(type default)
			)
			(layer "F.Fab")
		)
		(fp_line
			(start 0.120396 0.2794)
			(end -0.12065 0.2794)
			(stroke
				(width 0.1)
				(type default)
			)
			(layer "F.Fab")
		)
		(fp_line
			(start -0.12065 0.3048)
			(end -0.67945 0.3048)
			(stroke
				(width 0.1)
				(type default)
			)
			(layer "F.Fab")
		)
		(fp_line
			(start -0.12065 0.2794)
			(end -0.12065 0.3048)
			(stroke
				(width 0.1)
				(type default)
			)
			(layer "F.Fab")
		)
		(fp_line
			(start -0.12065 -0.2794)
			(end 0.12065 -0.2794)
			(stroke
				(width 0.1)
				(type default)
			)
			(layer "F.Fab")
		)
		(fp_line
			(start -0.12065 -0.305054)
			(end -0.12065 -0.2794)
			(stroke
				(width 0.1)
				(type default)
			)
			(layer "F.Fab")
		)
		(fp_line
			(start -0.67945 0.3048)
			(end -0.67945 -0.305054)
			(stroke
				(width 0.1)
				(type default)
			)
			(layer "F.Fab")
		)
		(fp_line
			(start -0.67945 -0.305054)
			(end -0.12065 -0.305054)
			(stroke
				(width 0.1)
				(type default)
			)
			(layer "F.Fab")
		)
		(pad "1" smd circle
			(at -0.40005 0 180)
			(size 0 0)
			(layers "F.Cu" "F.Mask" "F.Paste")
			(net "SPI_SYS_WP_R_IO2")
		)
		(pad "2" smd circle
			(at 0.40005 0 180)
			(size 0 0)
			(layers "F.Cu" "F.Mask" "F.Paste")
			(net "SPI_SYS_MUX_WP_IO2")
		)
	)
)
